# S9S_MB_2U (Grand Teton) — schematic netlist excerpt (pin names and nets, part order shuffled) for the footprints in the layout excerpt that follows; sources: Cadence DE-HDL packaged netlist, KiCad conversion of 03242023_DA0F0TMBIJ0_F0T_Motherboard_J_brd_V01_OCP.brd

J30  SCONN288_ADR50017P087CC  SCONN288_ADR50017-P087CC IO  pkg DDR288S_1-1VXB  page 111
  VIN_BULK0  = P12V_S3_AUX_CPU1_NVDIMM
  RFU0  = TP_CHG_CPU1_DIMM2_FRU_0
  VIN_MGMT  = P3V3_AUX
  HSCL  = I3C_SPD_DDREFGH_CPU1_LVC1_SCL_5
  HSDA  = I3C_SPD_DDREFGH_CPU1_LVC1_SDA
  VSS0  = GND
  DQ0_A  = M_G_CPU1_SA_DQ<0>
  VSS1  = GND
  DQ1_A  = M_G_CPU1_SA_DQ<1>
  VSS2  = GND
  DQS0_A_T  = M_G_CPU1_SA_DQS_DP<0>
  DQS0_A_C  = M_G_CPU1_SA_DQS_DN<0>
  VSS3  = GND
  DQ4_A  = M_G_CPU1_SA_DQ<4>
  VSS4  = GND
  DQ5_A  = M_G_CPU1_SA_DQ<5>
  VSS5  = GND
  DQ8_A  = M_G_CPU1_SA_DQ<8>
  VSS6  = GND
  DQ9_A  = M_G_CPU1_SA_DQ<9>
  VSS7  = GND
  DQS1_A_T  = M_G_CPU1_SA_DQS_DP<1>
  DQS1_A_C  = M_G_CPU1_SA_DQS_DN<1>
  VSS8  = GND
  DQ12_A  = M_G_CPU1_SA_DQ<12>
  VSS9  = GND
  DQ13_A  = M_G_CPU1_SA_DQ<13>
  VSS10  = GND
  DQ16_A  = M_G_CPU1_SA_DQ<16>
  VSS11  = GND
  DQ17_A  = M_G_CPU1_SA_DQ<17>
  VSS12  = GND
  DQS2_A_T  = M_G_CPU1_SA_DQS_DP<2>
  DQS2_A_C  = M_G_CPU1_SA_DQS_DN<2>
  VSS13  = GND
  DQ20_A  = M_G_CPU1_SA_DQ<20>
  VSS14  = GND
  DQ21_A  = M_G_CPU1_SA_DQ<21>
  VSS15  = GND
  DQ24_A  = M_G_CPU1_SA_DQ<24>
  VSS16  = GND
  DQ25_A  = M_G_CPU1_SA_DQ<25>
  VSS17  = GND
  DQS3_A_T  = M_G_CPU1_SA_DQS_DP<3>
  DQS3_A_C  = M_G_CPU1_SA_DQS_DN<3>
  VSS18  = GND
  DQ28_A  = M_G_CPU1_SA_DQ<28>
  VSS19  = GND
  DQ29_A  = M_G_CPU1_SA_DQ<29>
  VSS20  = GND
  CB0_A  = M_G_CPU1_SA_CB<0>
  VSS21  = GND
  CB1_A  = M_G_CPU1_SA_CB<1>
  VSS22  = GND
  DQS4_A_T  = M_G_CPU1_SA_DQS_DP<4>
  DQS4_A_C  = M_G_CPU1_SA_DQS_DN<4>
  VSS23  = GND
  CB4_A  = M_G_CPU1_SA_CB<4>
  VSS24  = GND
  CB5_A  = M_G_CPU1_SA_CB<5>
  VSS25  = GND
  ALERT_N  = M_G_CPU1_ALERT_N
  VSS26  = GND
  CS0_A_N  = M_G_CPU1_SA_CS_N<2>
  VSS27  = GND
  CA0_A  = M_G_CPU1_SA_CA<0>
  VSS28  = GND
  CA2_A  = M_G_CPU1_SA_CA<2>
  VSS29  = GND
  CA4_A  = M_G_CPU1_SA_CA<4>
  VSS30  = GND
  CA6_A  = M_G_CPU1_SA_CA<6>
  VSS31  = GND
  PAR_A  = M_G_CPU1_SA_PAR
  VSS32  = GND
  CA0_B  = M_G_CPU1_SB_CA<0>
  VSS33  = GND
  CA2_B  = M_G_CPU1_SB_CA<2>
  VSS34  = GND
  CA4_B  = M_G_CPU1_SB_CA<4>
  VSS35  = GND
  CA6_B  = M_G_CPU1_SB_CA<6>
  VSS36  = GND
  CS0_B_N  = M_G_CPU1_SB_CS_N<2>
  VSS37  = GND
  \lbd||rsp_a_n\  = M_G_CPU1_SA_RSP<1>
  \lbs||rsp_b_n\  = M_G_CPU1_SB_RSP<1>
  VSS38  = GND
  CB4_B  = M_G_CPU1_SB_CB<4>
  VSS39  = GND
  CB5_B  = M_G_CPU1_SB_CB<5>
  VSS40  = GND
  \dqs9_b_t||tdqs9_b_t||dbi4_b_n\  = M_G_CPU1_SB_DQS_DP<9>
  \dqs9_b_c||tdqs9_b_c\  = M_G_CPU1_SB_DQS_DN<9>
  VSS41  = GND
  CB0_B  = M_G_CPU1_SB_CB<0>
  VSS42  = GND
  CB1_B  = M_G_CPU1_SB_CB<1>
  VSS43  = GND
  DQ0_B  = M_G_CPU1_SB_DQ<0>
  VSS44  = GND
  DQ1_B  = M_G_CPU1_SB_DQ<1>
  VSS45  = GND
  DQS0_B_T  = M_G_CPU1_SB_DQS_DP<0>
  DQS0_B_C  = M_G_CPU1_SB_DQS_DN<0>
  VSS46  = GND
  DQ4_B  = M_G_CPU1_SB_DQ<4>
  VSS47  = GND
  DQ5_B  = M_G_CPU1_SB_DQ<5>
  VSS48  = GND
  DQ8_B  = M_G_CPU1_SB_DQ<8>
  VSS49  = GND
  DQ9_B  = M_G_CPU1_SB_DQ<9>
  VSS50  = GND
  DQS1_B_T  = M_G_CPU1_SB_DQS_DP<1>
  DQS1_B_C  = M_G_CPU1_SB_DQS_DN<1>
  VSS51  = GND
  DQ12_B  = M_G_CPU1_SB_DQ<12>
  VSS52  = GND
  DQ13_B  = M_G_CPU1_SB_DQ<13>
  VSS53  = GND
  DQ16_B  = M_G_CPU1_SB_DQ<16>
  VSS54  = GND
  DQ17_B  = M_G_CPU1_SB_DQ<17>
  VSS55  = GND
  DQS2_B_T  = M_G_CPU1_SB_DQS_DP<2>
  DQS2_B_C  = M_G_CPU1_SB_DQS_DN<2>
  VSS56  = GND
  DQ20_B  = M_G_CPU1_SB_DQ<20>
  VSS57  = GND
  DQ21_B  = M_G_CPU1_SB_DQ<21>
  VSS58  = GND
  DQ24_B  = M_G_CPU1_SB_DQ<24>
  VSS59  = GND
  DQ25_B  = M_G_CPU1_SB_DQ<25>
  VSS60  = GND
  DQS3_B_T  = M_G_CPU1_SB_DQS_DP<3>
  DQS3_B_C  = M_G_CPU1_SB_DQS_DN<3>
  VSS61  = GND
  DQ28_B  = M_G_CPU1_SB_DQ<28>
  VSS62  = GND
  DQ29_B  = M_G_CPU1_SB_DQ<29>
  VSS63  = GND
  RFU1  = TP_CHG_CPU1_DIMM2_FRU_1
  VIN_BULK1  = P12V_S3_AUX_CPU1_NVDIMM
  VIN_BULK2  = P12V_S3_AUX_CPU1_NVDIMM
  \pwr_good||fail_n\  = PWRGD_CHG_CPU1_DIMM2
  HSA  = PD_CHG_CPU1_DIMM2_SAA
  RFU2  = TP_CHG_CPU1_DIMM2_FRU_2
  RFU3  = TP_CHG_CPU1_DIMM2_FRU_3
  VSS64  = GND
  DQ2_A  = M_G_CPU1_SA_DQ<2>
  VSS65  = GND
  DQ3_A  = M_G_CPU1_SA_DQ<3>
  VSS66  = GND
  \dqs5_a_c||tdqs5_a_c||dqs5_a_t||tdqs5_a_t\  = M_G_CPU1_SA_DQS_DN<5>
  \dqs5_a_t||tdqs5_a_t\  = M_G_CPU1_SA_DQS_DP<5>
  VSS67  = GND
  DQ6_A  = M_G_CPU1_SA_DQ<6>
  VSS68  = GND
  DQ7_A  = M_G_CPU1_SA_DQ<7>
  VSS69  = GND
  DQ10_A  = M_G_CPU1_SA_DQ<10>
  VSS70  = GND
  DQ11_A  = M_G_CPU1_SA_DQ<11>
  VSS71  = GND
  \dqs6_a_c||tdqs6_a_c||dqs6_a_t||tdqs6_a_t\  = M_G_CPU1_SA_DQS_DN<6>
  \dqs6_a_t||tdqs6_a_t\  = M_G_CPU1_SA_DQS_DP<6>
  VSS72  = GND
  DQ14_A  = M_G_CPU1_SA_DQ<14>
  VSS73  = GND
  DQ15_A  = M_G_CPU1_SA_DQ<15>
  VSS74  = GND
  DQ18_A  = M_G_CPU1_SA_DQ<18>
  VSS75  = GND
  DQ19_A  = M_G_CPU1_SA_DQ<19>
  VSS76  = GND
  \dqs7_a_c||tdqs7_a_c\  = M_G_CPU1_SA_DQS_DN<7>
  \dqs7_a_t||tdqs7_a_t\  = M_G_CPU1_SA_DQS_DP<7>
  VSS77  = GND
  DQ22_A  = M_G_CPU1_SA_DQ<22>
  VSS78  = GND
  DQ23_A  = M_G_CPU1_SA_DQ<23>
  VSS79  = GND
  DQ26_A  = M_G_CPU1_SA_DQ<26>
  VSS80  = GND
  DQ27_A  = M_G_CPU1_SA_DQ<27>
  VSS81  = GND
  \dqs8_a_c||tdqs8_a_c\  = M_G_CPU1_SA_DQS_DN<8>
  \dqs8_a_t||tdqs8_a_t\  = M_G_CPU1_SA_DQS_DP<8>
  VSS82  = GND
  DQ30_A  = M_G_CPU1_SA_DQ<30>
  VSS83  = GND
  DQ31_A  = M_G_CPU1_SA_DQ<31>
  VSS84  = GND
  CB2_A  = M_G_CPU1_SA_CB<2>
  VSS85  = GND
  CB3_A  = M_G_CPU1_SA_CB<3>
  VSS86  = GND
  \dqs9_a_c||tdqs9_a_c\  = M_G_CPU1_SA_DQS_DN<9>
  \dqs9_a_t||tdqs9_a_t\  = M_G_CPU1_SA_DQS_DP<9>
  VSS87  = GND
  CB6_A  = M_G_CPU1_SA_CB<6>
  VSS88  = GND
  CB7_A  = M_G_CPU1_SA_CB<7>
  VSS89  = GND
  RESET_N  = RST_M_GH_CPU1_FPGA_N
  VSS90  = GND
  CS1_A_N  = M_G_CPU1_SA_CS_N<3>
  VSS91  = GND
  CA1_A  = M_G_CPU1_SA_CA<1>
  VSS92  = GND
  CA3_A  = M_G_CPU1_SA_CA<3>
  VSS93  = GND
  CA5_A  = M_G_CPU1_SA_CA<5>
  VSS94  = GND
  CK_T  = M_G_CPU1_CLK_DP<1>
  CK_C  = M_G_CPU1_CLK_DN<1>
  VSS95  = GND
  RFU4  = TP_CHG_CPU1_DIMM2_FRU_4
  CA1_B  = M_G_CPU1_SB_CA<1>
  VSS96  = GND
  CA3_B  = M_G_CPU1_SB_CA<3>
  VSS97  = GND
  CA5_B  = M_G_CPU1_SB_CA<5>
  VSS98  = GND
  PAR_B  = M_G_CPU1_SB_PAR
  VSS99  = GND
  CS1_B_N  = M_G_CPU1_SB_CS_N<3>
  VSS100  = GND
  RFU5  = TP_CHG_CPU1_DIMM2_FRU_5
  RFU6  = TP_CHG_CPU1_DIMM2_FRU_6
  VSS101  = GND
  CB6_B  = M_G_CPU1_SB_CB<6>
  VSS102  = GND
  CB7_B  = M_G_CPU1_SB_CB<7>
  VSS103  = GND
  DQS4_B_C  = M_G_CPU1_SB_DQS_DN<4>
  DQS4_B_T  = M_G_CPU1_SB_DQS_DP<4>
  VSS104  = GND
  CB2_B  = M_G_CPU1_SB_CB<2>
  VSS105  = GND
  CB3_B  = M_G_CPU1_SB_CB<3>
  VSS106  = GND
  DQ2_B  = M_G_CPU1_SB_DQ<2>
  VSS107  = GND
  DQ3_B  = M_G_CPU1_SB_DQ<3>
  VSS108  = GND
  \dqs5_b_c||tdqs5_b_c\  = M_G_CPU1_SB_DQS_DN<5>
  \dqs5_b_t||tdqs5_b_t\  = M_G_CPU1_SB_DQS_DP<5>
  VSS109  = GND
  DQ6_B  = M_G_CPU1_SB_DQ<6>
  VSS110  = GND
  DQ7_B  = M_G_CPU1_SB_DQ<7>
  VSS111  = GND
  DQ10_B  = M_G_CPU1_SB_DQ<10>
  VSS112  = GND
  DQ11_B  = M_G_CPU1_SB_DQ<11>
  VSS113  = GND
  \dqs6_b_c||tdqs6_b_c\  = M_G_CPU1_SB_DQS_DN<6>
  \dqs6_b_t||tdqs6_b_t\  = M_G_CPU1_SB_DQS_DP<6>
  VSS114  = GND
  DQ14_B  = M_G_CPU1_SB_DQ<14>
  VSS115  = GND
  DQ15_B  = M_G_CPU1_SB_DQ<15>
  VSS116  = GND
  DQ18_B  = M_G_CPU1_SB_DQ<18>
  VSS117  = GND
  DQ19_B  = M_G_CPU1_SB_DQ<19>
  VSS118  = GND
  \dqs7_b_c||tdqs7_b_c\  = M_G_CPU1_SB_DQS_DN<7>
  \dqs7_b_t||tdqs7_b_t\  = M_G_CPU1_SB_DQS_DP<7>
  VSS119  = GND
  DQ22_B  = M_G_CPU1_SB_DQ<22>
  VSS120  = GND
  DQ23_B  = M_G_CPU1_SB_DQ<23>
  VSS121  = GND
  DQ26_B  = M_G_CPU1_SB_DQ<26>
  VSS122  = GND
  DQ27_B  = M_G_CPU1_SB_DQ<27>
  VSS123  = GND
  \dqs8_b_c||tdqs8_b_c\  = M_G_CPU1_SB_DQS_DN<8>
  \dqs8_b_t||tdqs8_b_t\  = M_G_CPU1_SB_DQS_DP<8>
  VSS124  = GND
  DQ30_B  = M_G_CPU1_SB_DQ<30>
  VSS125  = GND
  DQ31_B  = M_G_CPU1_SB_DQ<31>
  VSS126  = GND
  G1  = GND
  G2  = GND
  G3  = GND

(kicad_pcb
	(version 20260206)
	(generator "pcbnew")
	(generator_version "10.0")
	(general
		(thickness 1.6)
		(legacy_teardrops no)
	)
	(paper "A4")
	(title_block
		(title "03242023_DA0F0TMBIJ0_F0T_Motherboard_J_brd_V01_OCP.brd")
		(comment 1 "Grand Teton / footprint 1354 of 6105 (J30), pads 46-91 of 291")
	)
	(layers
		(0 "F.Cu" signal "TOP")
		(4 "In1.Cu" signal "GND")
		(6 "In2.Cu" signal "IN1")
		(8 "In3.Cu" signal "GND1")
		(10 "In4.Cu" signal "IN2")
		(12 "In5.Cu" signal "GND2")
		(14 "In6.Cu" signal "IN3")
		(16 "In7.Cu" signal "GND3")
		(18 "In8.Cu" signal "VCC")
		(20 "In9.Cu" signal "VCC1")
		(22 "In10.Cu" signal "GND4")
		(24 "In11.Cu" signal "IN4")
		(26 "In12.Cu" signal "GND5")
		(28 "In13.Cu" signal "IN5")
		(30 "In14.Cu" signal "GND6")
		(32 "In15.Cu" signal "IN6")
		(34 "In16.Cu" signal "GND7")
		(2 "B.Cu" signal "BOTTOM")
		(9 "F.Adhes" user "F.Adhesive")
		(11 "B.Adhes" user "B.Adhesive")
		(13 "F.Paste" user "Package Geometry/Pastemask Top")
		(15 "B.Paste" user "Package Geometry/Pastemask Bottom")
		(5 "F.SilkS" user "Ref Des/Silkscreen Top")
		(7 "B.SilkS" user "Ref Des/Silkscreen Bottom")
		(1 "F.Mask" user "Board Geometry/Soldermask Top")
		(3 "B.Mask" user "Board Geometry/Soldermask Bottom")
		(17 "Dwgs.User" user "User.Drawings")
		(19 "Cmts.User" user "User.Comments")
		(21 "Eco1.User" user "User.Eco1")
		(23 "Eco2.User" user "User.Eco2")
		(25 "Edge.Cuts" user "Board Geometry/Outline")
		(27 "Margin" user)
		(31 "F.CrtYd" user "Package Geometry/Place Bound Top")
		(29 "B.CrtYd" user "Package Geometry/Place Bound Bottom")
		(35 "F.Fab" user "Ref Des/Assembly Top")
		(33 "B.Fab" user "Ref Des/Assembly Bottom")
	)
	(footprint ""
		(layer "F.Cu")
		(at 191.03848 -258.091686)
		(property "Reference" "J30"
			(at -2.98196 -81.740248 0)
			(unlocked yes)
			(layer "F.SilkS")
			(effects
				(font
					(size 0.7874 0.5842)
					(thickness 0.1524)
				)
				(justify left)
			)
		)
		(property "Value" ""
			(at 0 0 0)
			(layer "F.Fab")
			(effects
				(font
					(size 1.27 1.27)
				)
			)
		)
		(duplicate_pad_numbers_are_jumpers no)
		(pad "46" smd rect
			(at -2.050034 -25.07488 270)
			(size 0.519938 1.4986)
			(layers "F.Cu" "F.Mask" "F.Paste")
			(net "GND")
		)
		(pad "47" smd rect
			(at -2.050034 -24.224996 270)
			(size 0.519938 1.4986)
			(layers "F.Cu" "F.Mask" "F.Paste")
			(net "M_G_CPU1_SA_DQ<28>")
		)
		(pad "48" smd rect
			(at -2.050034 -23.375112 270)
			(size 0.519938 1.4986)
			(layers "F.Cu" "F.Mask" "F.Paste")
			(net "GND")
		)
		(pad "49" smd rect
			(at -2.050034 -22.524974 270)
			(size 0.519938 1.4986)
			(layers "F.Cu" "F.Mask" "F.Paste")
			(net "M_G_CPU1_SA_DQ<29>")
		)
		(pad "50" smd rect
			(at -2.050034 -21.67509 270)
			(size 0.519938 1.4986)
			(layers "F.Cu" "F.Mask" "F.Paste")
			(net "GND")
		)
		(pad "51" smd rect
			(at -2.050034 -20.824952 270)
			(size 0.519938 1.4986)
			(layers "F.Cu" "F.Mask" "F.Paste")
			(net "M_G_CPU1_SA_CB<0>")
		)
		(pad "52" smd rect
			(at -2.050034 -19.975068 270)
			(size 0.519938 1.4986)
			(layers "F.Cu" "F.Mask" "F.Paste")
			(net "GND")
		)
		(pad "53" smd rect
			(at -2.050034 -19.12493 270)
			(size 0.519938 1.4986)
			(layers "F.Cu" "F.Mask" "F.Paste")
			(net "M_G_CPU1_SA_CB<1>")
		)
		(pad "54" smd rect
			(at -2.050034 -18.275046 270)
			(size 0.519938 1.4986)
			(layers "F.Cu" "F.Mask" "F.Paste")
			(net "GND")
		)
		(pad "55" smd rect
			(at -2.050034 -17.424908 270)
			(size 0.519938 1.4986)
			(layers "F.Cu" "F.Mask" "F.Paste")
			(net "M_G_CPU1_SA_DQS_DP<4>")
		)
		(pad "56" smd rect
			(at -2.050034 -16.575024 270)
			(size 0.519938 1.4986)
			(layers "F.Cu" "F.Mask" "F.Paste")
			(net "M_G_CPU1_SA_DQS_DN<4>")
		)
		(pad "57" smd rect
			(at -2.050034 -15.724886 270)
			(size 0.519938 1.4986)
			(layers "F.Cu" "F.Mask" "F.Paste")
			(net "GND")
		)
		(pad "58" smd rect
			(at -2.050034 -14.875002 270)
			(size 0.519938 1.4986)
			(layers "F.Cu" "F.Mask" "F.Paste")
			(net "M_G_CPU1_SA_CB<4>")
		)
		(pad "59" smd rect
			(at -2.050034 -14.025118 270)
			(size 0.519938 1.4986)
			(layers "F.Cu" "F.Mask" "F.Paste")
			(net "GND")
		)
		(pad "60" smd rect
			(at -2.050034 -13.17498 270)
			(size 0.519938 1.4986)
			(layers "F.Cu" "F.Mask" "F.Paste")
			(net "M_G_CPU1_SA_CB<5>")
		)
		(pad "61" smd rect
			(at -2.050034 -12.325096 270)
			(size 0.519938 1.4986)
			(layers "F.Cu" "F.Mask" "F.Paste")
			(net "GND")
		)
		(pad "62" smd rect
			(at -2.050034 -11.474958 270)
			(size 0.519938 1.4986)
			(layers "F.Cu" "F.Mask" "F.Paste")
			(net "M_G_CPU1_ALERT_N")
		)
		(pad "63" smd rect
			(at -2.050034 -10.625074 270)
			(size 0.519938 1.4986)
			(layers "F.Cu" "F.Mask" "F.Paste")
			(net "GND")
		)
		(pad "64" smd rect
			(at -2.050034 -9.774936 270)
			(size 0.519938 1.4986)
			(layers "F.Cu" "F.Mask" "F.Paste")
			(net "M_G_CPU1_SA_CS_N<2>")
		)
		(pad "65" smd rect
			(at -2.050034 -8.925052 270)
			(size 0.519938 1.4986)
			(layers "F.Cu" "F.Mask" "F.Paste")
			(net "GND")
		)
		(pad "66" smd rect
			(at -2.050034 -8.074914 270)
			(size 0.519938 1.4986)
			(layers "F.Cu" "F.Mask" "F.Paste")
			(net "M_G_CPU1_SA_CA<0>")
		)
		(pad "67" smd rect
			(at -2.050034 -7.22503 270)
			(size 0.519938 1.4986)
			(layers "F.Cu" "F.Mask" "F.Paste")
			(net "GND")
		)
		(pad "68" smd rect
			(at -2.050034 -6.374892 270)
			(size 0.519938 1.4986)
			(layers "F.Cu" "F.Mask" "F.Paste")
			(net "M_G_CPU1_SA_CA<2>")
		)
		(pad "69" smd rect
			(at -2.050034 -5.525008 270)
			(size 0.519938 1.4986)
			(layers "F.Cu" "F.Mask" "F.Paste")
			(net "GND")
		)
		(pad "70" smd rect
			(at -2.050034 -4.675124 270)
			(size 0.519938 1.4986)
			(layers "F.Cu" "F.Mask" "F.Paste")
			(net "M_G_CPU1_SA_CA<4>")
		)
		(pad "71" smd rect
			(at -2.050034 -3.824986 270)
			(size 0.519938 1.4986)
			(layers "F.Cu" "F.Mask" "F.Paste")
			(net "GND")
		)
		(pad "72" smd rect
			(at -2.050034 -2.975102 270)
			(size 0.519938 1.4986)
			(layers "F.Cu" "F.Mask" "F.Paste")
			(net "M_G_CPU1_SA_CA<6>")
		)
		(pad "73" smd rect
			(at -2.050034 -2.124964 270)
			(size 0.519938 1.4986)
			(layers "F.Cu" "F.Mask" "F.Paste")
			(net "GND")
		)
		(pad "74" smd rect
			(at -2.050034 -1.27508 270)
			(size 0.519938 1.4986)
			(layers "F.Cu" "F.Mask" "F.Paste")
			(net "M_G_CPU1_SA_PAR")
		)
		(pad "75" smd rect
			(at -2.050034 -0.424942 270)
			(size 0.519938 1.4986)
			(layers "F.Cu" "F.Mask" "F.Paste")
			(net "GND")
		)
		(pad "76" smd rect
			(at -2.050034 5.525008 270)
			(size 0.519938 1.4986)
			(layers "F.Cu" "F.Mask" "F.Paste")
			(net "M_G_CPU1_SB_CA<0>")
		)
		(pad "77" smd rect
			(at -2.050034 6.374892 270)
			(size 0.519938 1.4986)
			(layers "F.Cu" "F.Mask" "F.Paste")
			(net "GND")
		)
		(pad "78" smd rect
			(at -2.050034 7.22503 270)
			(size 0.519938 1.4986)
			(layers "F.Cu" "F.Mask" "F.Paste")
			(net "M_G_CPU1_SB_CA<2>")
		)
		(pad "79" smd rect
			(at -2.050034 8.074914 270)
			(size 0.519938 1.4986)
			(layers "F.Cu" "F.Mask" "F.Paste")
			(net "GND")
		)
		(pad "80" smd rect
			(at -2.050034 8.925052 270)
			(size 0.519938 1.4986)
			(layers "F.Cu" "F.Mask" "F.Paste")
			(net "M_G_CPU1_SB_CA<4>")
		)
		(pad "81" smd rect
			(at -2.050034 9.774936 270)
			(size 0.519938 1.4986)
			(layers "F.Cu" "F.Mask" "F.Paste")
			(net "GND")
		)
		(pad "82" smd rect
			(at -2.050034 10.625074 270)
			(size 0.519938 1.4986)
			(layers "F.Cu" "F.Mask" "F.Paste")
			(net "M_G_CPU1_SB_CA<6>")
		)
		(pad "83" smd rect
			(at -2.050034 11.474958 270)
			(size 0.519938 1.4986)
			(layers "F.Cu" "F.Mask" "F.Paste")
			(net "GND")
		)
		(pad "84" smd rect
			(at -2.050034 12.325096 270)
			(size 0.519938 1.4986)
			(layers "F.Cu" "F.Mask" "F.Paste")
			(net "M_G_CPU1_SB_CS_N<2>")
		)
		(pad "85" smd rect
			(at -2.050034 13.17498 270)
			(size 0.519938 1.4986)
			(layers "F.Cu" "F.Mask" "F.Paste")
			(net "GND")
		)
		(pad "86" smd rect
			(at -2.050034 14.025118 270)
			(size 0.519938 1.4986)
			(layers "F.Cu" "F.Mask" "F.Paste")
			(net "M_G_CPU1_SA_RSP<1>")
		)
		(pad "87" smd rect
			(at -2.050034 14.875002 270)
			(size 0.519938 1.4986)
			(layers "F.Cu" "F.Mask" "F.Paste")
			(net "M_G_CPU1_SB_RSP<1>")
		)
		(pad "88" smd rect
			(at -2.050034 15.724886 270)
			(size 0.519938 1.4986)
			(layers "F.Cu" "F.Mask" "F.Paste")
			(net "GND")
		)
		(pad "89" smd rect
			(at -2.050034 16.575024 270)
			(size 0.519938 1.4986)
			(layers "F.Cu" "F.Mask" "F.Paste")
			(net "M_G_CPU1_SB_CB<4>")
		)
		(pad "90" smd rect
			(at -2.050034 17.424908 270)
			(size 0.519938 1.4986)
			(layers "F.Cu" "F.Mask" "F.Paste")
			(net "GND")
		)
		(pad "91" smd rect
			(at -2.050034 18.275046 270)
			(size 0.519938 1.4986)
			(layers "F.Cu" "F.Mask" "F.Paste")
			(net "M_G_CPU1_SB_CB<5>")
		)
	)
)
